# T6G (Grand Teton) — schematic netlist excerpt (pin names and nets, part order shuffled) for the footprints in the layout excerpt that follows; sources: Cadence DE-HDL packaged netlist, KiCad conversion of 04192023_DAF0TMB3IC0_F0TG_MB_C_brd_V02_OCP.brd

PC6524  Q_CAP  1UF 25V 10% X6S  pkg C0402  page 361 : A = SW_P12V_AUX_P1V8_RETIMER_CPU1_FLT ; B = GND
R798  Q_RES  33 5% CHIP  pkg 0402LF  page 81 : A = RST_PERST_M2_0_R_N ; B = RST_PERST_M2_0_N

(kicad_pcb
	(version 20260206)
	(generator "pcbnew")
	(generator_version "10.0")
	(general
		(thickness 1.6)
		(legacy_teardrops no)
	)
	(paper "A4")
	(title_block
		(title "04192023_DAF0TMB3IC0_F0TG_MB_C_brd_V02_OCP.brd")
		(comment 1 "Grand Teton / footprints 1649-1650 of 8354")
	)
	(layers
		(0 "F.Cu" signal "TOP")
		(4 "In1.Cu" signal "GND")
		(6 "In2.Cu" signal "IN1")
		(8 "In3.Cu" signal "GND1")
		(10 "In4.Cu" signal "IN2")
		(12 "In5.Cu" signal "GND2")
		(14 "In6.Cu" signal "IN3")
		(16 "In7.Cu" signal "GND3")
		(18 "In8.Cu" signal "VCC")
		(20 "In9.Cu" signal "VCC1")
		(22 "In10.Cu" signal "GND4")
		(24 "In11.Cu" signal "IN4")
		(26 "In12.Cu" signal "GND5")
		(28 "In13.Cu" signal "IN5")
		(30 "In14.Cu" signal "GND6")
		(32 "In15.Cu" signal "IN6")
		(34 "In16.Cu" signal "GND7")
		(2 "B.Cu" signal "BOTTOM")
		(9 "F.Adhes" user "F.Adhesive")
		(11 "B.Adhes" user "B.Adhesive")
		(13 "F.Paste" user "Package Geometry/Pastemask Top")
		(15 "B.Paste" user "Package Geometry/Pastemask Bottom")
		(5 "F.SilkS" user "Ref Des/Silkscreen Top")
		(7 "B.SilkS" user "Ref Des/Silkscreen Bottom")
		(1 "F.Mask" user "Board Geometry/Soldermask Top")
		(3 "B.Mask" user "Board Geometry/Soldermask Bottom")
		(17 "Dwgs.User" user "User.Drawings")
		(19 "Cmts.User" user "User.Comments")
		(21 "Eco1.User" user "User.Eco1")
		(23 "Eco2.User" user "User.Eco2")
		(25 "Edge.Cuts" user "Board Geometry/Outline")
		(27 "Margin" user)
		(31 "F.CrtYd" user "Package Geometry/Place Bound Top")
		(29 "B.CrtYd" user "Package Geometry/Place Bound Bottom")
		(35 "F.Fab" user "Ref Des/Assembly Top")
		(33 "B.Fab" user "Ref Des/Assembly Bottom")
	)
	(footprint ""
		(layer "F.Cu")
		(at 230.644192 -294.936926 180)
		(property "Reference" "PC6524"
			(at 0 0 180)
			(layer "F.SilkS")
			(hide yes)
			(effects
				(font
					(size 1.27 1.27)
				)
			)
		)
		(property "Value" ""
			(at 0 0 180)
			(layer "F.Fab")
			(effects
				(font
					(size 1.27 1.27)
				)
			)
		)
		(duplicate_pad_numbers_are_jumpers no)
		(fp_line
			(start 0.7874 0.4064)
			(end -0.7874 0.4064)
			(stroke
				(width 0.1524)
				(type default)
			)
			(layer "F.SilkS")
		)
		(fp_line
			(start 0.7874 -0.4064)
			(end 0.7874 0.4064)
			(stroke
				(width 0.1524)
				(type default)
			)
			(layer "F.SilkS")
		)
		(fp_line
			(start -0.7874 0.4064)
			(end -0.7874 -0.4064)
			(stroke
				(width 0.1524)
				(type default)
			)
			(layer "F.SilkS")
		)
		(fp_line
			(start -0.7874 -0.4064)
			(end 0.7874 -0.4064)
			(stroke
				(width 0.1524)
				(type default)
			)
			(layer "F.SilkS")
		)
		(fp_line
			(start 0.67945 0.3048)
			(end 0.120396 0.3048)
			(stroke
				(width 0.1)
				(type default)
			)
			(layer "F.Fab")
		)
		(fp_line
			(start 0.67945 -0.3048)
			(end 0.67945 0.3048)
			(stroke
				(width 0.1)
				(type default)
			)
			(layer "F.Fab")
		)
		(fp_line
			(start 0.12065 -0.2794)
			(end 0.12065 -0.3048)
			(stroke
				(width 0.1)
				(type default)
			)
			(layer "F.Fab")
		)
		(fp_line
			(start 0.12065 -0.3048)
			(end 0.67945 -0.3048)
			(stroke
				(width 0.1)
				(type default)
			)
			(layer "F.Fab")
		)
		(fp_line
			(start 0.120396 0.3048)
			(end 0.120396 0.2794)
			(stroke
				(width 0.1)
				(type default)
			)
			(layer "F.Fab")
		)
		(fp_line
			(start 0.120396 0.2794)
			(end -0.12065 0.2794)
			(stroke
				(width 0.1)
				(type default)
			)
			(layer "F.Fab")
		)
		(fp_line
			(start -0.12065 0.3048)
			(end -0.67945 0.3048)
			(stroke
				(width 0.1)
				(type default)
			)
			(layer "F.Fab")
		)
		(fp_line
			(start -0.12065 0.2794)
			(end -0.12065 0.3048)
			(stroke
				(width 0.1)
				(type default)
			)
			(layer "F.Fab")
		)
		(fp_line
			(start -0.12065 -0.2794)
			(end 0.12065 -0.2794)
			(stroke
				(width 0.1)
				(type default)
			)
			(layer "F.Fab")
		)
		(fp_line
			(start -0.12065 -0.305054)
			(end -0.12065 -0.2794)
			(stroke
				(width 0.1)
				(type default)
			)
			(layer "F.Fab")
		)
		(fp_line
			(start -0.67945 0.3048)
			(end -0.67945 -0.305054)
			(stroke
				(width 0.1)
				(type default)
			)
			(layer "F.Fab")
		)
		(fp_line
			(start -0.67945 -0.305054)
			(end -0.12065 -0.305054)
			(stroke
				(width 0.1)
				(type default)
			)
			(layer "F.Fab")
		)
		(pad "1" smd circle
			(at -0.40005 0 180)
			(size 0 0)
			(layers "F.Cu" "F.Mask" "F.Paste")
			(net "SW_P12V_AUX_P1V8_RETIMER_CPU1_FLT")
		)
		(pad "2" smd circle
			(at 0.40005 0 180)
			(size 0 0)
			(layers "F.Cu" "F.Mask" "F.Paste")
			(net "GND")
		)
	)
	(footprint ""
		(layer "F.Cu")
		(at 197.269608 -119.975376)
		(property "Reference" "R798"
			(at 0 0 0)
			(layer "F.SilkS")
			(hide yes)
			(effects
				(font
					(size 1.27 1.27)
				)
			)
		)
		(property "Value" ""
			(at 0 0 0)
			(layer "F.Fab")
			(effects
				(font
					(size 1.27 1.27)
				)
			)
		)
		(duplicate_pad_numbers_are_jumpers no)
		(fp_line
			(start -0.7874 -0.4064)
			(end 0.7874 -0.4064)
			(stroke
				(width 0.1524)
				(type default)
			)
			(layer "F.SilkS")
		)
		(fp_line
			(start -0.7874 0.4064)
			(end -0.7874 -0.4064)
			(stroke
				(width 0.1524)
				(type default)
			)
			(layer "F.SilkS")
		)
		(fp_line
			(start 0.7874 -0.4064)
			(end 0.7874 0.4064)
			(stroke
				(width 0.1524)
				(type default)
			)
			(layer "F.SilkS")
		)
		(fp_line
			(start 0.7874 0.4064)
			(end -0.7874 0.4064)
			(stroke
				(width 0.1524)
				(type default)
			)
			(layer "F.SilkS")
		)
		(fp_line
			(start -0.67945 -0.305054)
			(end -0.12065 -0.305054)
			(stroke
				(width 0.1)
				(type default)
			)
			(layer "F.Fab")
		)
		(fp_line
			(start -0.67945 0.3048)
			(end -0.67945 -0.305054)
			(stroke
				(width 0.1)
				(type default)
			)
			(layer "F.Fab")
		)
		(fp_line
			(start -0.12065 -0.305054)
			(end -0.12065 -0.2794)
			(stroke
				(width 0.1)
				(type default)
			)
			(layer "F.Fab")
		)
		(fp_line
			(start -0.12065 -0.2794)
			(end 0.12065 -0.2794)
			(stroke
				(width 0.1)
				(type default)
			)
			(layer "F.Fab")
		)
		(fp_line
			(start -0.12065 0.2794)
			(end -0.12065 0.3048)
			(stroke
				(width 0.1)
				(type default)
			)
			(layer "F.Fab")
		)
		(fp_line
			(start -0.12065 0.3048)
			(end -0.67945 0.3048)
			(stroke
				(width 0.1)
				(type default)
			)
			(layer "F.Fab")
		)
		(fp_line
			(start 0.120396 0.2794)
			(end -0.12065 0.2794)
			(stroke
				(width 0.1)
				(type default)
			)
			(layer "F.Fab")
		)
		(fp_line
			(start 0.120396 0.3048)
			(end 0.120396 0.2794)
			(stroke
				(width 0.1)
				(type default)
			)
			(layer "F.Fab")
		)
		(fp_line
			(start 0.12065 -0.3048)
			(end 0.67945 -0.3048)
			(stroke
				(width 0.1)
				(type default)
			)
			(layer "F.Fab")
		)
		(fp_line
			(start 0.12065 -0.2794)
			(end 0.12065 -0.3048)
			(stroke
				(width 0.1)
				(type default)
			)
			(layer "F.Fab")
		)
		(fp_line
			(start 0.67945 -0.3048)
			(end 0.67945 0.3048)
			(stroke
				(width 0.1)
				(type default)
			)
			(layer "F.Fab")
		)
		(fp_line
			(start 0.67945 0.3048)
			(end 0.120396 0.3048)
			(stroke
				(width 0.1)
				(type default)
			)
			(layer "F.Fab")
		)
		(pad "1" smd circle
			(at -0.40005 0)
			(size 0 0)
			(layers "F.Cu" "F.Mask" "F.Paste")
			(net "RST_PERST_M2_0_R_N")
		)
		(pad "2" smd circle
			(at 0.40005 0)
			(size 0 0)
			(layers "F.Cu" "F.Mask" "F.Paste")
			(net "RST_PERST_M2_0_N")
		)
	)
)
